# T6G (Grand Teton) — schematic netlist excerpt (pin names and nets, part order shuffled) for the footprints in the layout excerpt that follows; sources: Cadence DE-HDL packaged netlist, KiCad conversion of 04192023_DAF0TMB3IC0_F0TG_MB_C_brd_V02_OCP.brd

R138  Q_RES  4.7K 1% EMPTY  pkg 0402LF  page 144 : A = M2_SSD0_CLKREQ_EN_N ; B = GND
R1341  Q_RES  2.2K 5% CHIP  pkg 0402LF  page 252 : A = P3V3_AUX ; B = SMB_ADC_SDA_R

(kicad_pcb
	(version 20260206)
	(generator "pcbnew")
	(generator_version "10.0")
	(general
		(thickness 1.6)
		(legacy_teardrops no)
	)
	(paper "A4")
	(title_block
		(title "04192023_DAF0TMB3IC0_F0TG_MB_C_brd_V02_OCP.brd")
		(comment 1 "Grand Teton / footprints 1654-1655 of 8354")
	)
	(layers
		(0 "F.Cu" signal "TOP")
		(4 "In1.Cu" signal "GND")
		(6 "In2.Cu" signal "IN1")
		(8 "In3.Cu" signal "GND1")
		(10 "In4.Cu" signal "IN2")
		(12 "In5.Cu" signal "GND2")
		(14 "In6.Cu" signal "IN3")
		(16 "In7.Cu" signal "GND3")
		(18 "In8.Cu" signal "VCC")
		(20 "In9.Cu" signal "VCC1")
		(22 "In10.Cu" signal "GND4")
		(24 "In11.Cu" signal "IN4")
		(26 "In12.Cu" signal "GND5")
		(28 "In13.Cu" signal "IN5")
		(30 "In14.Cu" signal "GND6")
		(32 "In15.Cu" signal "IN6")
		(34 "In16.Cu" signal "GND7")
		(2 "B.Cu" signal "BOTTOM")
		(9 "F.Adhes" user "F.Adhesive")
		(11 "B.Adhes" user "B.Adhesive")
		(13 "F.Paste" user "Package Geometry/Pastemask Top")
		(15 "B.Paste" user "Package Geometry/Pastemask Bottom")
		(5 "F.SilkS" user "Ref Des/Silkscreen Top")
		(7 "B.SilkS" user "Ref Des/Silkscreen Bottom")
		(1 "F.Mask" user "Board Geometry/Soldermask Top")
		(3 "B.Mask" user "Board Geometry/Soldermask Bottom")
		(17 "Dwgs.User" user "User.Drawings")
		(19 "Cmts.User" user "User.Comments")
		(21 "Eco1.User" user "User.Eco1")
		(23 "Eco2.User" user "User.Eco2")
		(25 "Edge.Cuts" user "Board Geometry/Outline")
		(27 "Margin" user)
		(31 "F.CrtYd" user "Package Geometry/Place Bound Top")
		(29 "B.CrtYd" user "Package Geometry/Place Bound Bottom")
		(35 "F.Fab" user "Ref Des/Assembly Top")
		(33 "B.Fab" user "Ref Des/Assembly Bottom")
	)
	(footprint ""
		(layer "F.Cu")
		(at 273.378676 -118.618 180)
		(property "Reference" "R1341"
			(at 0 0 180)
			(layer "F.SilkS")
			(hide yes)
			(effects
				(font
					(size 1.27 1.27)
				)
			)
		)
		(property "Value" ""
			(at 0 0 180)
			(layer "F.Fab")
			(effects
				(font
					(size 1.27 1.27)
				)
			)
		)
		(duplicate_pad_numbers_are_jumpers no)
		(fp_line
			(start 0.7874 0.4064)
			(end -0.7874 0.4064)
			(stroke
				(width 0.1524)
				(type default)
			)
			(layer "F.SilkS")
		)
		(fp_line
			(start 0.7874 -0.4064)
			(end 0.7874 0.4064)
			(stroke
				(width 0.1524)
				(type default)
			)
			(layer "F.SilkS")
		)
		(fp_line
			(start -0.7874 0.4064)
			(end -0.7874 -0.4064)
			(stroke
				(width 0.1524)
				(type default)
			)
			(layer "F.SilkS")
		)
		(fp_line
			(start -0.7874 -0.4064)
			(end 0.7874 -0.4064)
			(stroke
				(width 0.1524)
				(type default)
			)
			(layer "F.SilkS")
		)
		(fp_line
			(start 0.67945 0.3048)
			(end 0.120396 0.3048)
			(stroke
				(width 0.1)
				(type default)
			)
			(layer "F.Fab")
		)
		(fp_line
			(start 0.67945 -0.3048)
			(end 0.67945 0.3048)
			(stroke
				(width 0.1)
				(type default)
			)
			(layer "F.Fab")
		)
		(fp_line
			(start 0.12065 -0.2794)
			(end 0.12065 -0.3048)
			(stroke
				(width 0.1)
				(type default)
			)
			(layer "F.Fab")
		)
		(fp_line
			(start 0.12065 -0.3048)
			(end 0.67945 -0.3048)
			(stroke
				(width 0.1)
				(type default)
			)
			(layer "F.Fab")
		)
		(fp_line
			(start 0.120396 0.3048)
			(end 0.120396 0.2794)
			(stroke
				(width 0.1)
				(type default)
			)
			(layer "F.Fab")
		)
		(fp_line
			(start 0.120396 0.2794)
			(end -0.12065 0.2794)
			(stroke
				(width 0.1)
				(type default)
			)
			(layer "F.Fab")
		)
		(fp_line
			(start -0.12065 0.3048)
			(end -0.67945 0.3048)
			(stroke
				(width 0.1)
				(type default)
			)
			(layer "F.Fab")
		)
		(fp_line
			(start -0.12065 0.2794)
			(end -0.12065 0.3048)
			(stroke
				(width 0.1)
				(type default)
			)
			(layer "F.Fab")
		)
		(fp_line
			(start -0.12065 -0.2794)
			(end 0.12065 -0.2794)
			(stroke
				(width 0.1)
				(type default)
			)
			(layer "F.Fab")
		)
		(fp_line
			(start -0.12065 -0.305054)
			(end -0.12065 -0.2794)
			(stroke
				(width 0.1)
				(type default)
			)
			(layer "F.Fab")
		)
		(fp_line
			(start -0.67945 0.3048)
			(end -0.67945 -0.305054)
			(stroke
				(width 0.1)
				(type default)
			)
			(layer "F.Fab")
		)
		(fp_line
			(start -0.67945 -0.305054)
			(end -0.12065 -0.305054)
			(stroke
				(width 0.1)
				(type default)
			)
			(layer "F.Fab")
		)
		(pad "1" smd circle
			(at -0.40005 0 180)
			(size 0 0)
			(layers "F.Cu" "F.Mask" "F.Paste")
			(net "P3V3_AUX")
		)
		(pad "2" smd circle
			(at 0.40005 0 180)
			(size 0 0)
			(layers "F.Cu" "F.Mask" "F.Paste")
			(net "SMB_ADC_SDA_R")
		)
	)
	(footprint ""
		(layer "F.Cu")
		(at 164.557964 -44.247054)
		(property "Reference" "R138"
			(at 0 0 0)
			(layer "F.SilkS")
			(hide yes)
			(effects
				(font
					(size 1.27 1.27)
				)
			)
		)
		(property "Value" ""
			(at 0 0 0)
			(layer "F.Fab")
			(effects
				(font
					(size 1.27 1.27)
				)
			)
		)
		(duplicate_pad_numbers_are_jumpers no)
		(fp_line
			(start -0.7874 -0.4064)
			(end 0.7874 -0.4064)
			(stroke
				(width 0.1524)
				(type default)
			)
			(layer "F.SilkS")
		)
		(fp_line
			(start -0.7874 0.4064)
			(end -0.7874 -0.4064)
			(stroke
				(width 0.1524)
				(type default)
			)
			(layer "F.SilkS")
		)
		(fp_line
			(start 0.7874 -0.4064)
			(end 0.7874 0.4064)
			(stroke
				(width 0.1524)
				(type default)
			)
			(layer "F.SilkS")
		)
		(fp_line
			(start 0.7874 0.4064)
			(end -0.7874 0.4064)
			(stroke
				(width 0.1524)
				(type default)
			)
			(layer "F.SilkS")
		)
		(fp_line
			(start -0.67945 -0.305054)
			(end -0.12065 -0.305054)
			(stroke
				(width 0.1)
				(type default)
			)
			(layer "F.Fab")
		)
		(fp_line
			(start -0.67945 0.3048)
			(end -0.67945 -0.305054)
			(stroke
				(width 0.1)
				(type default)
			)
			(layer "F.Fab")
		)
		(fp_line
			(start -0.12065 -0.305054)
			(end -0.12065 -0.2794)
			(stroke
				(width 0.1)
				(type default)
			)
			(layer "F.Fab")
		)
		(fp_line
			(start -0.12065 -0.2794)
			(end 0.12065 -0.2794)
			(stroke
				(width 0.1)
				(type default)
			)
			(layer "F.Fab")
		)
		(fp_line
			(start -0.12065 0.2794)
			(end -0.12065 0.3048)
			(stroke
				(width 0.1)
				(type default)
			)
			(layer "F.Fab")
		)
		(fp_line
			(start -0.12065 0.3048)
			(end -0.67945 0.3048)
			(stroke
				(width 0.1)
				(type default)
			)
			(layer "F.Fab")
		)
		(fp_line
			(start 0.120396 0.2794)
			(end -0.12065 0.2794)
			(stroke
				(width 0.1)
				(type default)
			)
			(layer "F.Fab")
		)
		(fp_line
			(start 0.120396 0.3048)
			(end 0.120396 0.2794)
			(stroke
				(width 0.1)
				(type default)
			)
			(layer "F.Fab")
		)
		(fp_line
			(start 0.12065 -0.3048)
			(end 0.67945 -0.3048)
			(stroke
				(width 0.1)
				(type default)
			)
			(layer "F.Fab")
		)
		(fp_line
			(start 0.12065 -0.2794)
			(end 0.12065 -0.3048)
			(stroke
				(width 0.1)
				(type default)
			)
			(layer "F.Fab")
		)
		(fp_line
			(start 0.67945 -0.3048)
			(end 0.67945 0.3048)
			(stroke
				(width 0.1)
				(type default)
			)
			(layer "F.Fab")
		)
		(fp_line
			(start 0.67945 0.3048)
			(end 0.120396 0.3048)
			(stroke
				(width 0.1)
				(type default)
			)
			(layer "F.Fab")
		)
		(pad "1" smd circle
			(at -0.40005 0)
			(size 0 0)
			(layers "F.Cu" "F.Mask" "F.Paste")
			(net "M2_SSD0_CLKREQ_EN_N")
		)
		(pad "2" smd circle
			(at 0.40005 0)
			(size 0 0)
			(layers "F.Cu" "F.Mask" "F.Paste")
			(net "GND")
		)
	)
)
